# SCM (Grand Teton) — schematic netlist excerpt (pin names and nets, part order shuffled) for the footprints in the layout excerpt that follows; sources: Cadence DE-HDL packaged netlist, KiCad conversion of 12092022_DA0F0TMDCD0_F0T_Management_Board_D_brd_V3_OCP.brd

C95  Q_CAP  0.1UF 25V 10% X7R  pkg 0402  page 16 : A = P1V8_AUX ; B = GND
R246  Q_RES  2.2K 5% CHIP  pkg 0402LF  page 27 : A = P3V3_AUX ; B = SMB_BMC_MM2_SCL

(kicad_pcb
	(version 20260206)
	(generator "pcbnew")
	(generator_version "10.0")
	(general
		(thickness 1.6)
		(legacy_teardrops no)
	)
	(paper "A4")
	(title_block
		(title "12092022_DA0F0TMDCD0_F0T_Management_Board_D_brd_V3_OCP.brd")
		(comment 1 "Grand Teton / footprints 951-952 of 1440")
	)
	(layers
		(0 "F.Cu" signal "TOP")
		(4 "In1.Cu" signal "GND")
		(6 "In2.Cu" signal "IN1")
		(8 "In3.Cu" signal "GND1")
		(10 "In4.Cu" signal "IN2")
		(12 "In5.Cu" signal "VCC")
		(14 "In6.Cu" signal "VCC1")
		(16 "In7.Cu" signal "IN3")
		(18 "In8.Cu" signal "GND2")
		(20 "In9.Cu" signal "IN4")
		(22 "In10.Cu" signal "GND3")
		(2 "B.Cu" signal "BOTTOM")
		(9 "F.Adhes" user "F.Adhesive")
		(11 "B.Adhes" user "B.Adhesive")
		(13 "F.Paste" user "Package Geometry/Pastemask Top")
		(15 "B.Paste" user "Package Geometry/Pastemask Bottom")
		(5 "F.SilkS" user "Ref Des/Silkscreen Top")
		(7 "B.SilkS" user "Ref Des/Silkscreen Bottom")
		(1 "F.Mask" user "Board Geometry/Soldermask Top")
		(3 "B.Mask" user "Board Geometry/Soldermask Bottom")
		(17 "Dwgs.User" user "User.Drawings")
		(19 "Cmts.User" user "User.Comments")
		(21 "Eco1.User" user "User.Eco1")
		(23 "Eco2.User" user "User.Eco2")
		(25 "Edge.Cuts" user "Board Geometry/Outline")
		(27 "Margin" user)
		(31 "F.CrtYd" user "Package Geometry/Place Bound Top")
		(29 "B.CrtYd" user "Package Geometry/Place Bound Bottom")
		(35 "F.Fab" user "Ref Des/Assembly Top")
		(33 "B.Fab" user "Ref Des/Assembly Bottom")
	)
	(footprint ""
		(layer "B.Cu")
		(at 56.256174 -44.791884)
		(property "Reference" "C95"
			(at 0 0 0)
			(layer "B.SilkS")
			(hide yes)
			(effects
				(font
					(size 1.27 1.27)
				)
				(justify mirror)
			)
		)
		(property "Value" ""
			(at 0 0 0)
			(layer "B.Fab")
			(effects
				(font
					(size 1.27 1.27)
				)
				(justify mirror)
			)
		)
		(duplicate_pad_numbers_are_jumpers no)
		(fp_line
			(start -0.7874 -0.4064)
			(end -0.7874 0.4064)
			(stroke
				(width 0.1524)
				(type default)
			)
			(layer "B.SilkS")
		)
		(fp_line
			(start -0.7874 0.4064)
			(end 0.7874 0.4064)
			(stroke
				(width 0.1524)
				(type default)
			)
			(layer "B.SilkS")
		)
		(fp_line
			(start 0.7874 -0.4064)
			(end -0.7874 -0.4064)
			(stroke
				(width 0.1524)
				(type default)
			)
			(layer "B.SilkS")
		)
		(fp_line
			(start 0.7874 0.4064)
			(end 0.7874 -0.4064)
			(stroke
				(width 0.1524)
				(type default)
			)
			(layer "B.SilkS")
		)
		(fp_line
			(start -0.67945 -0.3048)
			(end -0.67945 0.3048)
			(stroke
				(width 0.1)
				(type default)
			)
			(layer "B.Fab")
		)
		(fp_line
			(start -0.67945 0.3048)
			(end -0.120396 0.3048)
			(stroke
				(width 0.1)
				(type default)
			)
			(layer "B.Fab")
		)
		(fp_line
			(start -0.12065 -0.3048)
			(end -0.67945 -0.3048)
			(stroke
				(width 0.1)
				(type default)
			)
			(layer "B.Fab")
		)
		(fp_line
			(start -0.12065 -0.2794)
			(end -0.12065 -0.3048)
			(stroke
				(width 0.1)
				(type default)
			)
			(layer "B.Fab")
		)
		(fp_line
			(start -0.120396 0.2794)
			(end 0.12065 0.2794)
			(stroke
				(width 0.1)
				(type default)
			)
			(layer "B.Fab")
		)
		(fp_line
			(start -0.120396 0.3048)
			(end -0.120396 0.2794)
			(stroke
				(width 0.1)
				(type default)
			)
			(layer "B.Fab")
		)
		(fp_line
			(start 0.12065 -0.305054)
			(end 0.12065 -0.2794)
			(stroke
				(width 0.1)
				(type default)
			)
			(layer "B.Fab")
		)
		(fp_line
			(start 0.12065 -0.2794)
			(end -0.12065 -0.2794)
			(stroke
				(width 0.1)
				(type default)
			)
			(layer "B.Fab")
		)
		(fp_line
			(start 0.12065 0.2794)
			(end 0.12065 0.3048)
			(stroke
				(width 0.1)
				(type default)
			)
			(layer "B.Fab")
		)
		(fp_line
			(start 0.12065 0.3048)
			(end 0.67945 0.3048)
			(stroke
				(width 0.1)
				(type default)
			)
			(layer "B.Fab")
		)
		(fp_line
			(start 0.67945 -0.305054)
			(end 0.12065 -0.305054)
			(stroke
				(width 0.1)
				(type default)
			)
			(layer "B.Fab")
		)
		(fp_line
			(start 0.67945 0.3048)
			(end 0.67945 -0.305054)
			(stroke
				(width 0.1)
				(type default)
			)
			(layer "B.Fab")
		)
		(pad "1" smd circle
			(at 0.40005 0 180)
			(size 0 0)
			(layers "B.Cu" "B.Mask" "B.Paste")
			(net "P1V8_AUX")
		)
		(pad "2" smd circle
			(at -0.40005 0 180)
			(size 0 0)
			(layers "B.Cu" "B.Mask" "B.Paste")
			(net "GND")
		)
	)
	(footprint ""
		(layer "B.Cu")
		(at 42.350182 -30.816804 -90)
		(property "Reference" "R246"
			(at 0 0 90)
			(layer "B.SilkS")
			(hide yes)
			(effects
				(font
					(size 1.27 1.27)
				)
				(justify mirror)
			)
		)
		(property "Value" ""
			(at 0 0 90)
			(layer "B.Fab")
			(effects
				(font
					(size 1.27 1.27)
				)
				(justify mirror)
			)
		)
		(duplicate_pad_numbers_are_jumpers no)
		(fp_line
			(start -0.7874 0.4064)
			(end 0.7874 0.4064)
			(stroke
				(width 0.1524)
				(type default)
			)
			(layer "B.SilkS")
		)
		(fp_line
			(start 0.7874 0.4064)
			(end 0.7874 -0.4064)
			(stroke
				(width 0.1524)
				(type default)
			)
			(layer "B.SilkS")
		)
		(fp_line
			(start -0.7874 -0.4064)
			(end -0.7874 0.4064)
			(stroke
				(width 0.1524)
				(type default)
			)
			(layer "B.SilkS")
		)
		(fp_line
			(start 0.7874 -0.4064)
			(end -0.7874 -0.4064)
			(stroke
				(width 0.1524)
				(type default)
			)
			(layer "B.SilkS")
		)
		(fp_line
			(start -0.67945 0.3048)
			(end -0.120396 0.3048)
			(stroke
				(width 0.1)
				(type default)
			)
			(layer "B.Fab")
		)
		(fp_line
			(start -0.120396 0.3048)
			(end -0.120396 0.2794)
			(stroke
				(width 0.1)
				(type default)
			)
			(layer "B.Fab")
		)
		(fp_line
			(start 0.12065 0.3048)
			(end 0.67945 0.3048)
			(stroke
				(width 0.1)
				(type default)
			)
			(layer "B.Fab")
		)
		(fp_line
			(start 0.67945 0.3048)
			(end 0.67945 -0.305054)
			(stroke
				(width 0.1)
				(type default)
			)
			(layer "B.Fab")
		)
		(fp_line
			(start -0.120396 0.2794)
			(end 0.12065 0.2794)
			(stroke
				(width 0.1)
				(type default)
			)
			(layer "B.Fab")
		)
		(fp_line
			(start 0.12065 0.2794)
			(end 0.12065 0.3048)
			(stroke
				(width 0.1)
				(type default)
			)
			(layer "B.Fab")
		)
		(fp_line
			(start -0.12065 -0.2794)
			(end -0.12065 -0.3048)
			(stroke
				(width 0.1)
				(type default)
			)
			(layer "B.Fab")
		)
		(fp_line
			(start 0.12065 -0.2794)
			(end -0.12065 -0.2794)
			(stroke
				(width 0.1)
				(type default)
			)
			(layer "B.Fab")
		)
		(fp_line
			(start -0.67945 -0.3048)
			(end -0.67945 0.3048)
			(stroke
				(width 0.1)
				(type default)
			)
			(layer "B.Fab")
		)
		(fp_line
			(start -0.12065 -0.3048)
			(end -0.67945 -0.3048)
			(stroke
				(width 0.1)
				(type default)
			)
			(layer "B.Fab")
		)
		(fp_line
			(start 0.12065 -0.305054)
			(end 0.12065 -0.2794)
			(stroke
				(width 0.1)
				(type default)
			)
			(layer "B.Fab")
		)
		(fp_line
			(start 0.67945 -0.305054)
			(end 0.12065 -0.305054)
			(stroke
				(width 0.1)
				(type default)
			)
			(layer "B.Fab")
		)
		(pad "1" smd circle
			(at 0.40005 0 90)
			(size 0 0)
			(layers "B.Cu" "B.Mask" "B.Paste")
			(net "P3V3_AUX")
		)
		(pad "2" smd circle
			(at -0.40005 0 90)
			(size 0 0)
			(layers "B.Cu" "B.Mask" "B.Paste")
			(net "SMB_BMC_MM2_SCL")
		)
	)
)
